# SCM (Grand Teton) — schematic netlist excerpt (pin names and nets, part order shuffled) for the footprints in the layout excerpt that follows; sources: Cadence DE-HDL packaged netlist, KiCad conversion of 12092022_DA0F0TMDCD0_F0T_Management_Board_D_brd_V3_OCP.brd

GF1  FCONN168_ME1016810202011_SCM  EMPTY  pkg GOLD_168P_ME1016813401311  page 10
  I2C_0_SCL  = SMB_BMC_MM14_R1_SCL
  I2C_0_SDA  = SMB_BMC_MM14_R1_SDA
  I2C_1_SCL  = SMB_BMC_MM1_SCL
  I2C_1_SDA  = SMB_BMC_MM1_SDA
  I2C_2_SCL  = SMB_BMC_MM2_SCL_R1
  I2C_2_SDA  = SMB_BMC_MM2_SDA
  I2C_3_SCL  = SMB_BMC_MM3_SCL
  I2C_3_SDA  = SMB_BMC_MM3_SDA
  I2C_4_SCL  = SMB_BMC_MM4_SCL
  I2C_4_SDA  = SMB_BMC_MM4_SDA
  I2C_5_SCL  = SMB_BMC_MM5_SCL
  I2C_5_SDA  = SMB_BMC_MM5_SDA
  GND_A13  = GND
  CLK_100M_PCIE_DP  = CLK_100M_PCH_DP
  CLK_100M_PCIE_DN  = CLK_100M_PCH_DN
  GND_A16  = GND
  PCIE_BMC_TX_DP  = P2E_PCH_RX_DP
  PCIE_BMC_TX_DN  = P2E_PCH_RX_DN
  GND_A19  = GND
  PCIE_BMC_RX_DP  = P2E_PCH_TX_C_DP
  PCIE_BMC_RX_DN  = P2E_PCH_TX_C_DN
  GND_A22  = GND
  I2C_6_SCL  = SMB_BMC_MM6_SCL
  I2C_6_SDA  = SMB_BMC_MM6_SDA
  I2C_7_SCL  = SMB_BMC_MM7_SCL
  I2C_7_SDA  = SMB_BMC_MM7_SDA
  I2C_8_SCL  = SMB_BMC_MM8_SCL
  I2C_8_SDA  = SMB_BMC_MM8_SDA
  I2C_9_SCL  = SMB_BMC_MM9_SCL
  I2C_9_SDA  = SMB_BMC_MM9_SDA
  I2C_10_SCL  = SMB_BMC_MM10_SCL
  I2C_10_SDA  = SMB_BMC_MM10_SDA
  GND_A33  = GND
  JTAG_TCK  = JTAG_MB_TCK
  JTAG_TMS  = JTAG_MB_TMS
  JTAG_TDI  = JTAG_MB_TDI
  JTAG_TDO  = JTAG_MB_TDO
  I2C_11_SCL  = SMB_BMC_MM12_SCL
  I2C_11_SDA  = SMB_BMC_MM12_SDA
  I2C_12_SCL  = SMB_BMC_MM13_SCL
  I2C_12_SDA  = SMB_BMC_MM13_SDA
  GND_A42  = GND
  HPM_FW_RECOVERY  = FM_JTAG_SEL
  HPM_STBY_RDY  = PWRGD_PSU_AC_PWROK_R
  HPM_STBY_EN  = TP_GF_A45
  HPM_STBY_RST_N  = RST_MB_STBY_N
  SYS_PWRBTN_N  = SYS_PWRBTN_N
  SYS_PWROK  = PWRGD_SYS_PWROK
  DBP_PREQ_N  = FM_DBP_CPU_PREQ_GF_R_N
  DBP_PRDY_N  = FM_DBP_BMC_PRDY_N
  RST_PLTRST_BUF_N  = RST_PLTRST_N
  SPARE1  = FM_BMC_UARTSW_MSB_N
  ROT_CPU_RST_N  = RST_ROT_CPU_N
  CHASI_N  = FM_INTRUDER_N
  SPARE0  = FM_BMC_UARTSW_LSB_N
  IRQ_N  = IRQ_SMI_ACTIVE_GF_N
  PRSNT1_N  = FM_PRSNT_1_N
  GND_A58  = GND
  PCIE_HPM_RXP_0  = USB3_FPNL_RXP
  PCIE_HPM_RXN_0  = USB3_FPNL_RXN
  GND_A61  = GND
  PCIE_HPM_RXP_1  = TP_GF_A62
  PCIE_HPM_RXN_1  = TP_GF_A63
  GND_A64  = GND
  PCIE_HPM_RXP_2  = P2E_GPU_RX_DP
  PCIE_HPM_RXN_2  = P2E_GPU_RX_DN
  GND_A67  = GND
  PCIE_HPM_RXP_3  = CLK_100M_GPU_DP
  PCIE_HPM_RXN_3  = CLK_100M_GPU_DN
  GND_A70  = GND
  ESPI_CLK  = ESPI_HOST_LPC_BMC_CLK
  ESPI_CS0_N  = ESPI_HOST_LPC_BMC_LFRAME_N
  ESPI_ALERT_N  = IRQ_BMC_LPC_SERIRQ_ESPI_GF
  ESPI_RESET_N  = RST_BMC_LPC_ESPI_N
  ESPI_IO0  = ESPI_LPC_LAD0_IO0
  ESPI_IO1  = ESPI_LPC_LAD1_IO1
  ESPI_IO2  = ESPI_LPC_LAD2_IO2
  ESPI_IO3  = ESPI_LPC_LAD3_IO3
  RSVD3  = LPC_ESPI_SEL
  GND_B10  = GND
  QSPI0_CLK  = SPI_SYS_R_CLK
  QSPI0_CS0_N  = SPI_SYS_CS0_N
  QSPI0_D0  = SPI_SYS_R_MOSI
  QSPI0_D1  = SPI_SYS_R_MISO
  QSPI0_D2  = SPI_SYS_WP_R_IO2
  QSPI0_D3  = SPI_SYS_HOLD_R_IO3
  GND_B17  = GND
  NCSI_CLK  = RMII_OCP_RCLKI
  NCSI_CRS_DV  = RMII_CSRDV
  NCSI_TXEN  = RMII_TXEN
  NCSI_TXD0  = RMII_TXD0
  NCSI_TXD1  = RMII_TXD1
  NCSI_RXER  = RMII_RXER
  NCSI_RXD0  = RMII_RXD0
  NCSI_RXD1  = RMII_RXD1
  GND_B26  = GND
  PECI_BMC  = PECI_BMC
  PVCCIO_PECI  = PVCCIO_PECI_BMC
  SGPIO0_DO  = SGPIO_DO_0
  SGPIO_CLK  = SGPIO_CLK_0
  SGPIO0_DI  = SGPIO_DI_0
  SGPIO0_LD  = SGPIO_LD_0
  GND_B33  = GND
  SGPIO1_DO  = SGPIO_DO_1
  RSVD2  = SGPIO_CLK_1
  SGPIO1_DI  = SGPIO_DI_1
  SGPIO1_LD  = SGPIO_LD_1
  GND_B38  = GND
  SGPIO_RESET_N  = RST_SGPIO_RESET_N
  SGPIO_INTR_N  = IRQ_SGPIO_N
  P3V0_BAT  = P3V_BAT_R
  QSPI0_CS1_N  = AC_PWR_BTN_N
  QSPI1_CLK  = QSPI_2_PLD_CLK
  QSPI1_CS0_N  = TP_GF1_B44
  QSPI1_D0  = QSPI_2_PLD_IO0
  QSPI1_D1  = QSPI_2_PLD_IO1
  QSPI1_D2  = QSPI_2_PLD_IO2
  QSPI1_D3  = QSPI_2_PLD_IO3
  GND_B49  = GND
  USB2_DP  = USB_HOST_BMC_B_DP
  USB2_DN  = USB_HOST_BMC_B_DN
  GND_B52  = GND
  USB1_DP  = USB_HOST_BMC_A_DP
  USB1_DN  = USB_HOST_BMC_A_DN
  GND_B55  = GND
  RSVD0  = USB_FPNL_DP
  RSVD1  = USB_FPNL_DN
  GND_B58  = GND
  PCIE_HPM_TXP_0  = USB3_FPNL_TXP
  PCIE_HPM_TXN_0  = USB3_FPNL_TXN
  GND_B61  = GND
  PCIE_HPM_TXP_1  = TP_GF_B62
  PCIE_HPM_TXN_1  = TP_GF_B63
  GND_B64  = GND
  PCIE_HPM_TXP_2  = P2E_GPU_TX_C_DP
  PCIE_HPM_TXN_2  = P2E_GPU_TX_C_DN
  GND_B67  = GND
  PCIE_HPM_TXP_3  = HDD_LED_R_N
  PCIE_HPM_TXN_3  = PCH_BEEP_R_LED
  GND_B70  = GND
  P12V_AUX_OA1  = P12V_AUX
  P12V_AUX_OA2  = P12V_AUX
  GND_OA3  = GND
  GND_OA4  = GND
  I3C_0_SCL  = I3C1_SPD_SCL
  I3C_0_SDA  = I3C1_SPD_SDA
  I3C_1_SCL  = I3C2_SPD_SCL
  I3C_1_SDA  = I3C2_SPD_SDA
  I3C_2_SCL  = I3C3_SPD_SCL
  I3C_2_SDA  = I3C3_SPD_SDA
  I3C_3_SCL  = I3C4_SPD_SCL
  I3C_3_SDA  = I3C4_SPD_SDA
  GND_OA13  = GND
  VIRTUAL_RESEAT  = FM_VIRTUAL_RESEAT
  P12V_AUX_OB1  = P12V_AUX
  P12V_AUX_OB2  = P12V_AUX
  PRSNT0_N  = FM_PRSNT_0_R_N
  GND_OB4  = GND
  UART1_SCM_TX  = UART_BIC_GF_TXD
  UART1_SCM_RX  = UART_BIC_GF_RXD
  GND_OB7  = GND
  UART0_SCM_TX  = UART_SYS_DBG_TX
  UART0_SCM_RX  = UART_SYS_DBG_RX
  GND_OB10  = GND
  SPI0_CLK  = RST_SRST_PLD_BMC_R_N
  SPI0_CS_N  = SPI_TPM_CS_N
  SPI0_MOSI  = H_CPU_CATERR_LVC2_R2_N
  SPI0_MISO  = FM_SOL_UART_CH_SEL

(kicad_pcb
	(version 20260206)
	(generator "pcbnew")
	(generator_version "10.0")
	(general
		(thickness 1.6)
		(legacy_teardrops no)
	)
	(paper "A4")
	(title_block
		(title "12092022_DA0F0TMDCD0_F0T_Management_Board_D_brd_V3_OCP.brd")
		(comment 1 "Grand Teton / footprint 804 of 1440 (GF1), pads 48-95 of 168")
	)
	(layers
		(0 "F.Cu" signal "TOP")
		(4 "In1.Cu" signal "GND")
		(6 "In2.Cu" signal "IN1")
		(8 "In3.Cu" signal "GND1")
		(10 "In4.Cu" signal "IN2")
		(12 "In5.Cu" signal "VCC")
		(14 "In6.Cu" signal "VCC1")
		(16 "In7.Cu" signal "IN3")
		(18 "In8.Cu" signal "GND2")
		(20 "In9.Cu" signal "IN4")
		(22 "In10.Cu" signal "GND3")
		(2 "B.Cu" signal "BOTTOM")
		(9 "F.Adhes" user "F.Adhesive")
		(11 "B.Adhes" user "B.Adhesive")
		(13 "F.Paste" user "Package Geometry/Pastemask Top")
		(15 "B.Paste" user "Package Geometry/Pastemask Bottom")
		(5 "F.SilkS" user "Ref Des/Silkscreen Top")
		(7 "B.SilkS" user "Ref Des/Silkscreen Bottom")
		(1 "F.Mask" user "Board Geometry/Soldermask Top")
		(3 "B.Mask" user "Board Geometry/Soldermask Bottom")
		(17 "Dwgs.User" user "User.Drawings")
		(19 "Cmts.User" user "User.Comments")
		(21 "Eco1.User" user "User.Eco1")
		(23 "Eco2.User" user "User.Eco2")
		(25 "Edge.Cuts" user "Board Geometry/Outline")
		(27 "Margin" user)
		(31 "F.CrtYd" user "Package Geometry/Place Bound Top")
		(29 "B.CrtYd" user "Package Geometry/Place Bound Bottom")
		(35 "F.Fab" user "Ref Des/Assembly Top")
		(33 "B.Fab" user "Ref Des/Assembly Bottom")
	)
	(footprint ""
		(layer "B.Cu")
		(at 45.260006 -114.324892 180)
		(property "Reference" "GF1"
			(at 30.591506 -4.763262 0)
			(unlocked yes)
			(layer "B.SilkS")
			(effects
				(font
					(size 0.7874 0.5842)
					(thickness 0.1524)
				)
				(justify left mirror)
			)
		)
		(property "Value" ""
			(at 0 0 0)
			(layer "B.Fab")
			(effects
				(font
					(size 1.27 1.27)
				)
				(justify mirror)
			)
		)
		(duplicate_pad_numbers_are_jumpers no)
		(pad "A48" smd rect
			(at 17.714976 3.934968)
			(size 0.381 1.7272)
			(layers "B.Cu" "B.Mask" "B.Paste")
			(net "PWRGD_SYS_PWROK")
		)
		(pad "A49" smd rect
			(at 18.314924 4.13512)
			(size 0.381 2.1336)
			(layers "B.Cu" "B.Mask" "B.Paste")
			(net "FM_DBP_CPU_PREQ_GF_R_N")
		)
		(pad "A50" smd rect
			(at 18.914872 3.934968)
			(size 0.381 1.7272)
			(layers "B.Cu" "B.Mask" "B.Paste")
			(net "FM_DBP_BMC_PRDY_N")
		)
		(pad "A51" smd rect
			(at 19.515074 3.934968)
			(size 0.381 1.7272)
			(layers "B.Cu" "B.Mask" "B.Paste")
			(net "RST_PLTRST_N")
		)
		(pad "A52" smd rect
			(at 20.115022 4.13512)
			(size 0.381 2.1336)
			(layers "B.Cu" "B.Mask" "B.Paste")
			(net "FM_BMC_UARTSW_MSB_N")
		)
		(pad "A53" smd rect
			(at 20.71497 3.934968)
			(size 0.381 1.7272)
			(layers "B.Cu" "B.Mask" "B.Paste")
			(net "RST_ROT_CPU_N")
		)
		(pad "A54" smd rect
			(at 21.314918 3.934968)
			(size 0.381 1.7272)
			(layers "B.Cu" "B.Mask" "B.Paste")
			(net "FM_INTRUDER_N")
		)
		(pad "A55" smd rect
			(at 21.91512 4.13512)
			(size 0.381 2.1336)
			(layers "B.Cu" "B.Mask" "B.Paste")
			(net "FM_BMC_UARTSW_LSB_N")
		)
		(pad "A56" smd rect
			(at 22.515068 3.934968)
			(size 0.381 1.7272)
			(layers "B.Cu" "B.Mask" "B.Paste")
			(net "IRQ_SMI_ACTIVE_GF_N")
		)
		(pad "A57" smd rect
			(at 23.115016 3.934968)
			(size 0.381 1.7272)
			(layers "B.Cu" "B.Mask" "B.Paste")
			(net "FM_PRSNT_1_N")
		)
		(pad "A58" smd rect
			(at 23.714964 4.13512)
			(size 0.381 2.1336)
			(layers "B.Cu" "B.Mask" "B.Paste")
			(net "GND")
		)
		(pad "A59" smd rect
			(at 24.314912 3.934968)
			(size 0.381 1.7272)
			(layers "B.Cu" "B.Mask" "B.Paste")
			(net "USB3_FPNL_RXP")
		)
		(pad "A60" smd rect
			(at 24.915114 3.934968)
			(size 0.381 1.7272)
			(layers "B.Cu" "B.Mask" "B.Paste")
			(net "USB3_FPNL_RXN")
		)
		(pad "A61" smd rect
			(at 25.515062 4.13512)
			(size 0.381 2.1336)
			(layers "B.Cu" "B.Mask" "B.Paste")
			(net "GND")
		)
		(pad "A62" smd rect
			(at 26.11501 3.934968)
			(size 0.381 1.7272)
			(layers "B.Cu" "B.Mask" "B.Paste")
			(net "TP_GF_A62")
		)
		(pad "A63" smd rect
			(at 26.714958 3.934968)
			(size 0.381 1.7272)
			(layers "B.Cu" "B.Mask" "B.Paste")
			(net "TP_GF_A63")
		)
		(pad "A64" smd rect
			(at 27.314906 4.13512)
			(size 0.381 2.1336)
			(layers "B.Cu" "B.Mask" "B.Paste")
			(net "GND")
		)
		(pad "A65" smd rect
			(at 27.915108 3.934968)
			(size 0.381 1.7272)
			(layers "B.Cu" "B.Mask" "B.Paste")
			(net "P2E_GPU_RX_DP")
		)
		(pad "A66" smd rect
			(at 28.515056 3.934968)
			(size 0.381 1.7272)
			(layers "B.Cu" "B.Mask" "B.Paste")
			(net "P2E_GPU_RX_DN")
		)
		(pad "A67" smd rect
			(at 29.115004 4.13512)
			(size 0.381 2.1336)
			(layers "B.Cu" "B.Mask" "B.Paste")
			(net "GND")
		)
		(pad "A68" smd rect
			(at 29.714952 3.934968)
			(size 0.381 1.7272)
			(layers "B.Cu" "B.Mask" "B.Paste")
			(net "CLK_100M_GPU_DP")
		)
		(pad "A69" smd rect
			(at 30.3149 3.934968)
			(size 0.381 1.7272)
			(layers "B.Cu" "B.Mask" "B.Paste")
			(net "CLK_100M_GPU_DN")
		)
		(pad "A70" smd rect
			(at 30.915102 4.13512)
			(size 0.381 2.1336)
			(layers "B.Cu" "B.Mask" "B.Paste")
			(net "GND")
		)
		(pad "B1" smd rect
			(at -18.204942 3.934968)
			(size 0.381 1.7272)
			(layers "B.Cu" "B.Mask" "B.Paste")
			(net "ESPI_HOST_LPC_BMC_CLK")
		)
		(pad "B2" smd rect
			(at -17.604994 3.934968)
			(size 0.381 1.7272)
			(layers "B.Cu" "B.Mask" "B.Paste")
			(net "ESPI_HOST_LPC_BMC_LFRAME_N")
		)
		(pad "B3" smd rect
			(at -17.005046 3.934968)
			(size 0.381 1.7272)
			(layers "B.Cu" "B.Mask" "B.Paste")
			(net "IRQ_BMC_LPC_SERIRQ_ESPI_GF")
		)
		(pad "B4" smd rect
			(at -16.405098 3.934968)
			(size 0.381 1.7272)
			(layers "B.Cu" "B.Mask" "B.Paste")
			(net "RST_BMC_LPC_ESPI_N")
		)
		(pad "B5" smd rect
			(at -15.804896 3.934968)
			(size 0.381 1.7272)
			(layers "B.Cu" "B.Mask" "B.Paste")
			(net "ESPI_LPC_LAD0_IO0")
		)
		(pad "B6" smd rect
			(at -15.204948 3.934968)
			(size 0.381 1.7272)
			(layers "B.Cu" "B.Mask" "B.Paste")
			(net "ESPI_LPC_LAD1_IO1")
		)
		(pad "B7" smd rect
			(at -14.605 3.934968)
			(size 0.381 1.7272)
			(layers "B.Cu" "B.Mask" "B.Paste")
			(net "ESPI_LPC_LAD2_IO2")
		)
		(pad "B8" smd rect
			(at -14.005052 3.934968)
			(size 0.381 1.7272)
			(layers "B.Cu" "B.Mask" "B.Paste")
			(net "ESPI_LPC_LAD3_IO3")
		)
		(pad "B9" smd rect
			(at -13.405104 3.934968)
			(size 0.381 1.7272)
			(layers "B.Cu" "B.Mask" "B.Paste")
			(net "LPC_ESPI_SEL")
		)
		(pad "B10" smd rect
			(at -12.804902 3.934968)
			(size 0.381 1.7272)
			(layers "B.Cu" "B.Mask" "B.Paste")
			(net "GND")
		)
		(pad "B11" smd rect
			(at -12.204954 3.934968)
			(size 0.381 1.7272)
			(layers "B.Cu" "B.Mask" "B.Paste")
			(net "SPI_SYS_R_CLK")
		)
		(pad "B12" smd rect
			(at -11.605006 3.934968)
			(size 0.381 1.7272)
			(layers "B.Cu" "B.Mask" "B.Paste")
			(net "SPI_SYS_CS0_N")
		)
		(pad "B13" smd rect
			(at -11.005058 4.13512)
			(size 0.381 2.1336)
			(layers "B.Cu" "B.Mask" "B.Paste")
			(net "SPI_SYS_R_MOSI")
		)
		(pad "B14" smd rect
			(at -10.40511 3.934968)
			(size 0.381 1.7272)
			(layers "B.Cu" "B.Mask" "B.Paste")
			(net "SPI_SYS_R_MISO")
		)
		(pad "B15" smd rect
			(at -9.804908 3.934968)
			(size 0.381 1.7272)
			(layers "B.Cu" "B.Mask" "B.Paste")
			(net "SPI_SYS_WP_R_IO2")
		)
		(pad "B16" smd rect
			(at -9.20496 4.13512)
			(size 0.381 2.1336)
			(layers "B.Cu" "B.Mask" "B.Paste")
			(net "SPI_SYS_HOLD_R_IO3")
		)
		(pad "B17" smd rect
			(at -8.605012 3.934968)
			(size 0.381 1.7272)
			(layers "B.Cu" "B.Mask" "B.Paste")
			(net "GND")
		)
		(pad "B18" smd rect
			(at -8.005064 3.934968)
			(size 0.381 1.7272)
			(layers "B.Cu" "B.Mask" "B.Paste")
			(net "RMII_OCP_RCLKI")
		)
		(pad "B19" smd rect
			(at -7.405116 4.13512)
			(size 0.381 2.1336)
			(layers "B.Cu" "B.Mask" "B.Paste")
			(net "RMII_CSRDV")
		)
		(pad "B20" smd rect
			(at -6.804914 3.934968)
			(size 0.381 1.7272)
			(layers "B.Cu" "B.Mask" "B.Paste")
			(net "RMII_TXEN")
		)
		(pad "B21" smd rect
			(at -6.204966 3.934968)
			(size 0.381 1.7272)
			(layers "B.Cu" "B.Mask" "B.Paste")
			(net "RMII_TXD0")
		)
		(pad "B22" smd rect
			(at -5.605018 4.13512)
			(size 0.381 2.1336)
			(layers "B.Cu" "B.Mask" "B.Paste")
			(net "RMII_TXD1")
		)
		(pad "B23" smd rect
			(at -5.00507 3.934968)
			(size 0.381 1.7272)
			(layers "B.Cu" "B.Mask" "B.Paste")
			(net "RMII_RXER")
		)
		(pad "B24" smd rect
			(at -4.405122 3.934968)
			(size 0.381 1.7272)
			(layers "B.Cu" "B.Mask" "B.Paste")
			(net "RMII_RXD0")
		)
		(pad "B25" smd rect
			(at -3.80492 4.13512)
			(size 0.381 2.1336)
			(layers "B.Cu" "B.Mask" "B.Paste")
			(net "RMII_RXD1")
		)
	)
)
